# SCM (Grand Teton) — schematic parts with pin connectivity, parts 518–678 of 1428; source: Cadence DE-HDL packaged netlist (pstxprt.dat, pstxnet.dat, pstchip.dat)

R11  Q_RES  4.7K 1% CHIP  pkg 0402LF  page 21 : 1 = P3V3_AUX ; 2 = BMC_EMMC_RST_N
R12  Q_RES  4.7K 1% EMPTY  pkg 0402LF  page 26 : 1 = P3V3_AUX ; 2 = FRU_E0
R13  Q_RES  4.7K 1% EMPTY  pkg 0402LF  page 26 : 1 = P3V3_AUX ; 2 = FRU_E1
R14  Q_RES  4.7K 1% EMPTY  pkg 0402LF  page 26 : 1 = P3V3_AUX ; 2 = FRU_E2
R15  Q_RES  1K 1% CHIP  pkg 0402LF  page 26 : 1 = PD_FRU_WC_N ; 2 = GND
R16  Q_RES  2.21K 1% EMPTY  pkg 0402LF  page 23 : 1 = V_BMC_LS_DDC_SCL_R ; 2 = CRT_VCC5
R17  Q_RES  2.21K 1% EMPTY  pkg 0402LF  page 23 : 1 = V_BMC_LS_DDC_SDA_R ; 2 = CRT_VCC5
R18  Q_RES  0 5% CHIP  pkg 0402LF  page 23 : 1 = P5V_AUX ; 2 = BMC_DDC_BUF_PWR
R19  Q_RES  0 5% CHIP  pkg 0402LF  page 15 : 1 = V_VGAHS_R ; 2 = V_VGAHS
R20  Q_RES  0 5% CHIP  pkg 0402LF  page 15 : 1 = V_VGAVS_R ; 2 = V_VGAVS
R21  Q_RES  10 1% CHIP  pkg 0402LF  page 15 : 1 = V_DACG_R ; 2 = V_DACG
R22  Q_RES  150 1% CHIP  pkg 0402LF  page 15 : 1 = V_DACB_R ; 2 = GND
R23  Q_RES  150 1% CHIP  pkg 0402LF  page 15 : 1 = V_DACG_R ; 2 = GND
R24  Q_RES  10 1% CHIP  pkg 0402LF  page 15 : 1 = V_DACB_R ; 2 = V_DACB
R25  Q_RES  150 1% CHIP  pkg 0402LF  page 15 : 1 = V_DACR_R ; 2 = GND
R26  Q_RES  10 1% CHIP  pkg 0402LF  page 15 : 1 = V_DACR_R ; 2 = V_DACR
R27  Q_RES  0 5% EMPTY  pkg 0603LF  page 23 : 1 = P5V_AUX ; 2 = CRT_VCC5
R28  Q_RES  33.2 1% CHIP  pkg 0402LF  page 23 : 1 = V_BMC_LS_DDC_SCL ; 2 = V_BMC_LS_DDC_SCL_R
R29  Q_RES  33.2 1% CHIP  pkg 0402LF  page 23 : 1 = V_BMC_LS_DDC_SDA ; 2 = V_BMC_LS_DDC_SDA_R
R30  Q_RES  0 5% CHIP  pkg 0402LF  page 23 : 1 = CRT_VCC5 ; 2 = BMC_DDC_BUF_EN
R31  Q_RES  4.7K 1% CHIP  pkg 0402LF  page 23 : 1 = P3V3_RGM ; 2 = V_BMC_DDC_SDA
R32  Q_RES  4.7K 1% CHIP  pkg 0402LF  page 23 : 1 = P3V3_RGM ; 2 = V_BMC_DDC_SCL
R33  Q_RES  33.2 1% CHIP  pkg 0402LF  page 46 : 1 = SMB_BMC_MM16_R5_SDA ; 2 = SMB_BMC_TPM_MM16_SDA
R34  Q_RES  4.7K 1% EMPTY  pkg 0402LF  page 11 : 1 = P3V3_RGM ; 2 = RST_PLTRST_N
R35  Q_RES  0 5% CHIP  pkg 0402LF  page 53 : 1 = PWRGD_P2V5_AUX ; 2 = PWRGD_P2V5_AUX_R
R36  Q_RES  33.2 1% CHIP  pkg 0402LF  page 10 : 1 = SMB_BMC_MM14_SCL ; 2 = SMB_BMC_MM14_R1_SCL
R37  Q_RES  33.2 1% CHIP  pkg 0402LF  page 13 : 1 = IRQ_SMI_ACTIVE_GF_N ; 2 = IRQ_SMI_ACTIVE_BMC_N
R38  Q_RES  4.7K 1% CHIP  pkg 0402LF  page 13 : 1 = P3V3_AUX ; 2 = FM_BMC_SUSACK_N
R39  Q_RES  0 5% CHIP  pkg 0402LF  page 30 : 1 = SPA_SOUT_SW_BUF_R ; 2 = SPA_SOUT_SW_BUF
R40  Q_RES  2K 1% EMPTY  pkg 0402LF  page 11 : 1 = GND ; 2 = PWRGD_SYS_PWROK
R41  Q_RES  10K 1% EMPTY  pkg 0402LF  page 11 : 1 = P3V3_AUX ; 2 = LPC_ESPI_SEL
R42  Q_RES  4.7K 1% CHIP  pkg 0402LF  page 27 : 1 = P3V3_AUX ; 2 = Q7_D
R43  Q_RES  220 1% CHIP  pkg 0402LF  page 49 : 1 = ID_LED_P3V3_AUX ; 2 = P3V3_AUX
R44  Q_RES  4.7K 1% EMPTY  pkg 0402LF  page 11 : 1 = P3V3_AUX ; 2 = SYS_PWRBTN_N
R45  Q_RES  4.7K 1% CHIP  pkg 0402LF  page 11 : 1 = P3V3_AUX ; 2 = FM_THROTTLE_N
R46  Q_RES  33.2 1% CHIP  pkg 0402LF  page 10 : 1 = SMB_BMC_MM14_SDA ; 2 = SMB_BMC_MM14_R1_SDA
R47  Q_RES  33.2 1% CHIP  pkg 0402LF  page 46 : 1 = SMB_BMC_TPM_MM16_SCL ; 2 = SMB_BMC_MM16_R5_SCL
R48  Q_RES  33.2 1% EMPTY  pkg 0402LF  page 21 : 1 = EMMC_CMD_R ; 2 = BMC_EMMC_CMD
R49  Q_RES  0 5% CHIP  pkg 0402LF  page 22 : 1 = PWRGD_P1V0_AUX ; 2 = PWRGD_P1V0_AUX_R2
R50  Q_RES  10K 1% CHIP  pkg 0402LF  page 46 : 1 = P3V3_AUX ; 2 = FM_TPM_PRSNT_1_N
R51  Q_RES  0 5% CHIP  pkg 0402LF  page 35 : 1 = H_CPU0_PROCHOT_LVC1_N ; 2 = H_CPU0_PROCHOT_LVC1_R_N
R52  Q_RES  4.7K 1% CHIP  pkg 0402LF  page 26 : 1 = P3V3_AUX ; 2 = TMC75_A1
R53  Q_RES  1K 1% EMPTY  pkg 0402LF  page 26 : 1 = TMC75_A1 ; 2 = GND
R54  Q_RES  10K 1% CHIP  pkg 0402LF  page 26 : 1 = SMB_BMC_ALERT16_R_N ; 2 = SMB_BMC_ALERT16_N
R55  Q_RES  4.7K 1% CHIP  pkg 0402LF  page 13 : 1 = P3V3_AUX ; 2 = FM_BMC_READY_R_PLD_N
R56  Q_RES  4.7K 1% CHIP  pkg 0402LF  page 13 : 1 = P3V3_AUX ; 2 = FM_BIOS_DEBUG_EN_R_N
R57  Q_RES  0 5% CHIP  pkg 0402LF  page 21 : 1 = BSM_PRSNT_R_N ; 2 = BSM_PRSNT_N
R58  Q_RES  4.7K 1% EMPTY  pkg 0402LF  page 21 : 1 = P3V3_AUX ; 2 = SPI_BMC_HOLD0_N
R59  Q_RES  10K 1% CHIP  pkg 0402LF  page 46 : 1 = P3V3_AUX ; 2 = IRQ_TPM_SPI_N
R60  Q_RES  33.2 1% CHIP  pkg 0402LF  page 13 : 1 = RST_ROT_CPU_R1_N ; 2 = RST_ROT_CPU_N
R61  Q_RES  4.7K 1% CHIP  pkg 0402LF  page 13 : 1 = P3V3_AUX ; 2 = IRQ_BMC_PCH_NMI_N
R62  Q_RES  4.7K 1% CHIP  pkg 0402LF  page 12 : 1 = P3V3_AUX ; 2 = FM_PCH_BMC_THERMTRIP_N
R63  Q_RES  0 5% EMPTY  pkg 0402LF  page 11 : 1 = SGPIO_CLK_1 ; 2 = GND
R64  Q_RES  0 5% EMPTY  pkg 0402LF  page 11 : 1 = SGPIO_CLK_0 ; 2 = GND
R65  Q_RES  33.2 1% CHIP  pkg 0402LF  page 13 : 1 = BMC_CPLD_GPIO_2_R1 ; 2 = BMC_CPLD_GPIO_2
R66  Q_RES  100K 1% CHIP  pkg 0402LF  page 11 : 1 = GND ; 2 = PWRGD_PSU_AC_PWROK
R67  Q_RES  4.7K 1% CHIP  pkg 0402LF  page 30 : 1 = P3V3_AUX ; 2 = UART_BMC_5_TXD_BUF1_R
R68  Q_RES  4.7K 1% CHIP  pkg 0402LF  page 11 : 1 = P3V3_AUX ; 2 = IRQ_SGPIO_N
R69  Q_RES  4.7K 1% CHIP  pkg 0402LF  page 11 : 1 = P3V3_AUX ; 2 = RST_SGPIO_RESET_N
R70  Q_RES  33.2 1% CHIP  pkg 0402LF  page 13 : 1 = RST_PCA9548_SENSOR_R_N ; 2 = RST_PCA9548_SENSOR_N
R71  Q_RES  33.2 1% CHIP  pkg 0402LF  page 12 : 1 = SMB_BMC_MM5_R_SCL ; 2 = SMB_BMC_MM5_SCL
R72  Q_RES  4.7K 1% CHIP  pkg 0402LF  page 30 : 1 = P3V3_AUX ; 2 = UART_BMC_5_RXD_BUF1
R73  Q_RES  1K 1% EMPTY  pkg 0402LF  page 11 : 1 = P3V3_AUX ; 2 = SGPIO_LD_1
R74  Q_RES  2K 1% CHIP  pkg 0402LF  page 11 : 1 = P3V3_AUX ; 2 = SGPIO_DI_1
R75  Q_RES  2K 1% CHIP  pkg 0402LF  page 11 : 1 = P3V3_AUX ; 2 = SGPIO_DO_1
R76  Q_RES  2K 1% CHIP  pkg 0402LF  page 11 : 1 = P3V3_AUX ; 2 = SGPIO_CLK_1
R77  Q_RES  1K 1% EMPTY  pkg 0402LF  page 11 : 1 = P3V3_AUX ; 2 = SGPIO_LD_0
R78  Q_RES  2K 1% CHIP  pkg 0402LF  page 11 : 1 = P3V3_AUX ; 2 = SGPIO_DI_0
R79  Q_RES  2K 1% CHIP  pkg 0402LF  page 11 : 1 = P3V3_AUX ; 2 = SGPIO_DO_0
R80  Q_RES  220 1% CHIP  pkg 0402LF  page 50 : 1 = LED_D22_R ; 2 = P5V_AUX
R81  Q_RES  4.7K 1% CHIP  pkg 0402LF  page 11 : 1 = P3V3_AUX ; 2 = PWR_BTN_BMC_N
R82  Q_RES  2K 1% CHIP  pkg 0402LF  page 11 : 1 = P3V3_AUX ; 2 = SGPIO_CLK_0
R83  Q_RES  0 5% CHIP  pkg 0402LF  page 28 : 1 = FM_UART_SEL_N ; 2 = FM_UART_SWITCH_N
R84  Q_RES  0 5% CHIP  pkg 0402LF  page 23 : 1 = V_VGAVS_BUF_R ; 2 = V_VGAVS_BUF
R85  Q_RES  0 5% CHIP  pkg 0402LF  page 23 : 1 = V_VGAHS_BUF_R ; 2 = V_VGAHS_BUF
R86  Q_RES  0 5% CHIP  pkg 0402LF  page 23 : 1 = P3V3_RGM ; 2 = V_BMC_DDC_LS_GATE
R87  Q_RES  150 1% CHIP  pkg 0402LF  page 23 : 1 = V_DACB_IO ; 2 = GND
R88  Q_RES  150 1% CHIP  pkg 0402LF  page 23 : 1 = V_DACG_IO ; 2 = GND
R89  Q_RES  150 1% CHIP  pkg 0402LF  page 23 : 1 = V_DACR_IO ; 2 = GND
R90  Q_RES  4.7K 1% EMPTY  pkg 0402LF  page 21 : 1 = P3V3_AUX ; 2 = RST_SPI_BMC_FLASH_R2_N
R91  Q_RES  2.2K 5% CHIP  pkg 0402LF  page 23 : 1 = CRT_VCC5 ; 2 = V_BMC_LS_DDC_SDA
R92  Q_RES  2.2K 5% CHIP  pkg 0402LF  page 23 : 1 = CRT_VCC5 ; 2 = V_BMC_LS_DDC_SCL
R93  Q_RES  33.2 1% CHIP  pkg 0402LF  page 12 : 1 = SMB_BMC_MM5_R_SDA ; 2 = SMB_BMC_MM5_SDA
R94  Q_RES  4.7K 1% CHIP  pkg 0402LF  page 27 : 1 = SPI_BMC_BOOT_MOSI ; 2 = GND
R95  Q_RES  0 5% CHIP  pkg 0402LF  page 28 : 1 = SMB_DEBUG_AUX_LVC3_USB_SDA ; 2 = SMB_DEBUG_AUX_LVC3_USB_R3_SDA
R96  Q_RES  33.2 1% CHIP  pkg 0402LF  page 13 : 1 = BMC_EMMC_RST_R_N ; 2 = BMC_EMMC_RST_N
R97  Q_RES  0 5% CHIP  pkg 0402LF  page 46 : 1 = SPI_BMC_TPM_MOSI_R ; 2 = SPI_BMC_TPM_MOSI
R98  Q_RES  0 5% CHIP  pkg 0402LF  page 46 : 1 = SPI_BMC_TPM_MISO_R ; 2 = SPI_BMC_TPM_MISO
R99  Q_RES  0 5% CHIP  pkg 0402LF  page 52 : 1 = PWRGD_P3V3_RGM_R ; 2 = PWRGD_P3V3_RGM
R100  Q_RES  33.2 1% CHIP  pkg 0402LF  page 46 : 1 = SPI_BMC_TPM_CS2_N_R ; 2 = SPI_BMC_TPM_CS2_R_N
R101  Q_RES  4.7K 1% CHIP  pkg 0402LF  page 11 : 1 = P3V3_AUX ; 2 = RMII_RXER
R102  Q_RES  33.2 1% CHIP  pkg 0402LF  page 30 : 1 = UART_BMC_5_TXD_BUF ; 2 = UART_BMC_5_TXD_BUF_R
R103  Q_RES  4.7K 1% CHIP  pkg 0402LF  page 11 : 1 = P3V3_AUX ; 2 = RMII_TXEN
R104  Q_RES  33.2 1% CHIP  pkg 0402LF  page 30 : 1 = UART_BMC_5_RXD_BUF_R ; 2 = UART_BMC_5_RXD_BUF1
R105  Q_RES  0 5% CHIP  pkg 0402LF  page 36 : 1 = SMB_BMC_MM16_R4_SCL ; 2 = SMB_BMC_MM16_R5_SCL
R106  Q_RES  0 5% EMPTY  pkg 0402LF  page 22 : 1 = RST_BMC_SRST_N ; 2 = RST_BMC_EXTRST_R2_N
R107  Q_RES  316 1% CHIP  pkg 0402LF  page 50 : 1 = LED_D21_R3 ; 2 = LED_D21_R2
R108  Q_RES  49.9 1% CHIP  pkg 0402LF  page 22 : 1 = RST_SRST_PLD_BMC_BUF_N ; 2 = RST_BMC_SRST_BUF_R_N
R109  Q_RES  0 5% CHIP  pkg 0402LF  page 46 : 1 = SPI_BMC_TPM_CLK_R ; 2 = SPI_BMC_TPM_CLK
R110  Q_RES  0 5% CHIP  pkg 0402LF  page 46 : 1 = RST_BMC_EXTRST_R3_N ; 2 = RST_BMC_EXTRST_R2_N
R111  Q_RES  33.2 1% CHIP  pkg 0402LF  page 13 : 1 = FM_BMC_READY_R_PLD_N ; 2 = FM_BMC_READY_PLD_N
R112  Q_RES  33.2 1% CHIP  pkg 0402LF  page 13 : 1 = FM_BIOS_DEBUG_EN_R_N ; 2 = FM_BIOS_DEBUG_EN_N
R113  Q_RES  0 5% CHIP  pkg 0402LF  page 46 : 1 = IRQ_TPM_SPI_N ; 2 = IRQ_BMC_TPM_SPI_R_N
R114  Q_RES  0 5% CHIP  pkg 0402LF  page 36 : 1 = SMB_BMC_MM16_R4_SDA ; 2 = SMB_BMC_MM16_R5_SDA
R115  Q_RES  4.7K 1% EMPTY  pkg 0402LF  page 12 : 1 = PGPPA_BMC_AUX ; 2 = ESPI_HOST_LPC_BMC_LFRAME_N
R116  Q_RES  4.7K 1% CHIP  pkg 0402LF  page 12 : 1 = PGPPA_BMC_AUX ; 2 = IRQ_BMC_LPC_SERIRQ_ESPI_GF
R117  Q_RES  4.7K 1% EMPTY  pkg 0402LF  page 12 : 1 = PGPPA_BMC_AUX ; 2 = RST_BMC_LPC_ESPI_N
R118  Q_RES  100K 1% CHIP  pkg 0402LF  page 12 : 1 = GND ; 2 = RST_PLTRST_N
R119  Q_RES  33.2 1% CHIP  pkg 0402LF  page 12 : 1 = IRQ_BMC_LPC_SERIRQ_ESPI_GF ; 2 = IRQ_ESPI_LPC_SERIRQ_ALERT0_N
R120  Q_RES  33.2 1% CHIP  pkg 0402LF  page 12 : 1 = RST_BMC_LPC_ESPI_N ; 2 = RST_ESPI_LPC_BMC_N
R121  Q_RES  33.2 1% CHIP  pkg 0402LF  page 13 : 1 = FM_CPU_RMCA_CATERR_LVT3_R_N ; 2 = FM_CPU_MSMI_CATERR_LVT3_N
R122  Q_RES  33.2 1% CHIP  pkg 0402LF  page 13 : 1 = FM_BIC_DEBUG_SW_N ; 2 = FM_BIC_DEBUG_SW_N_R
R123  Q_RES  33.2 1% CHIP  pkg 0402LF  page 34 : 1 = FM_TPM_PRSNT_1_N ; 2 = FM_TPM_PRSNT_1_R_N
R124  Q_RES  2K 1% CHIP  pkg 0402LF  page 22 : 1 = P3V3_AUX ; 2 = RST_BMC_SRST_BUF_R_N
R125  Q_RES  100 1% CHIP  pkg 0402LF  page 22 : 1 = RST_BMC_SRST_BUF_R_N ; 2 = RST_BMC_SRST_N
R126  Q_RES  10K 1% CHIP  pkg 0402LF  page 46 : 1 = SMB_PCH_TPM_SDA ; 2 = P3V3_AUX
R127  Q_RES  240 1% CHIP  pkg 0402LF  page 12 : 1 = GND ; 2 = IBMC_MIOZ
R128  Q_RES  22 1% CHIP  pkg 0402LF  page 12 : 1 = ESPI_LPC_D0_IO0 ; 2 = ESPI_LPC_LAD0_IO0
R129  Q_RES  22 1% CHIP  pkg 0402LF  page 12 : 1 = ESPI_LPC_D1_IO1 ; 2 = ESPI_LPC_LAD1_IO1
R130  Q_RES  22 1% CHIP  pkg 0402LF  page 12 : 1 = ESPI_LPC_D2_IO2 ; 2 = ESPI_LPC_LAD2_IO2
R131  Q_RES  22 1% CHIP  pkg 0402LF  page 12 : 1 = ESPI_LPC_D3_IO3 ; 2 = ESPI_LPC_LAD3_IO3
R132  Q_RES  33.2 1% CHIP  pkg 0402LF  page 12 : 1 = SMB_BMC_MM1_R_SCL ; 2 = SMB_BMC_MM1_SCL
R133  Q_RES  33.2 1% CHIP  pkg 0402LF  page 12 : 1 = SMB_BMC_MM1_R_SDA ; 2 = SMB_BMC_MM1_SDA
R134  Q_RES  0 5% CHIP  pkg 0402LF  page 36 : 1 = FM_BMC_UARTSW_LSB_N ; 2 = FM_UARTSW_LSB_N
R135  Q_RES  0 5% CHIP  pkg 0402LF  page 28 : 1 = SMB_BMC_MM15_SCL ; 2 = SMB_BMC_MM15_R1_SCL
R136  Q_RES  10K 1% CHIP  pkg 0402LF  page 46 : 1 = P3V3_AUX ; 2 = SMB_PCH_TPM_SCL
R137  Q_RES  33.2 1% CHIP  pkg 0402LF  page 12 : 1 = SMB_BMC_MM12_R_SCL ; 2 = SMB_BMC_MM12_SCL
R138  Q_RES  40.2 1% CHIP  pkg 0402LF  page 12 : 1 = SMB_BMC_MM4_R_SCL ; 2 = SMB_BMC_MM4_SCL
R139  Q_RES  33.2 1% CHIP  pkg 0402LF  page 12 : 1 = SMB_BMC_MM4_R_SDA ; 2 = SMB_BMC_MM4_SDA
R140  Q_RES  4.7K 1% EMPTY  pkg 0402LF  page 27 : 1 = P3V3_AUX ; 2 = SPI_BMC_BOOT_MOSI
R142  Q_RES  33.2 1% CHIP  pkg 0402LF  page 12 : 1 = SMB_BMC_MM6_R_SCL ; 2 = SMB_BMC_MM6_SCL
R143  Q_RES  33.2 1% CHIP  pkg 0402LF  page 12 : 1 = SMB_BMC_MM6_R_SDA ; 2 = SMB_BMC_MM6_SDA
R144  Q_RES  33.2 1% CHIP  pkg 0402LF  page 12 : 1 = SMB_BMC_MM12_R_SDA ; 2 = SMB_BMC_MM12_SDA
R145  Q_RES  10K 1% CHIP  pkg 0402LF  page 27 : 1 = P3V3_AUX ; 2 = SMB_BMC_MM12_SCL
R146  Q_RES  33.2 1% CHIP  pkg 0402LF  page 12 : 1 = SMB_BMC_MM8_R_SCL ; 2 = SMB_BMC_MM8_SCL
R147  Q_RES  33.2 1% CHIP  pkg 0402LF  page 12 : 1 = SMB_BMC_MM8_R_SDA ; 2 = SMB_BMC_MM8_SDA
R148  Q_RES  33.2 1% CHIP  pkg 0402LF  page 12 : 1 = SGPIO_CLK_1 ; 2 = SGPIO_BMC_M1_CLK
R149  Q_RES  10K 1% CHIP  pkg 0402LF  page 27 : 1 = P3V3_AUX ; 2 = SMB_BMC_MM12_SDA
R150  Q_RES  33.2 1% CHIP  pkg 0402LF  page 12 : 1 = SGPIO_LD_1 ; 2 = SGPIO_BMC_M1_LD
R151  Q_RES  33.2 1% CHIP  pkg 0402LF  page 12 : 1 = SGPIO_DO_1 ; 2 = SGPIO_BMC_M1_DO
R152  Q_RES  33.2 1% CHIP  pkg 0402LF  page 12 : 1 = SMB_BMC_MM16_SCL ; 2 = SMB_BMC_MM16_R_SCL
R153  Q_RES  33.2 1% CHIP  pkg 0402LF  page 12 : 1 = SMB_BMC_MM16_SDA ; 2 = SMB_BMC_MM16_R_SDA
R154  Q_RES  0 5% EMPTY  pkg 0402LF  page 13 : 1 = P1V8_AUX ; 2 = P3V3_P2V5_P1V8_RVDD
R155  Q_RES  0 5% CHIP  pkg 0402LF  page 13 : 1 = P3V3_AUX ; 2 = P3V3_P2V5_P1V8_RVDD
R156  Q_RES  0 5% EMPTY  pkg 0402LF  page 13 : 1 = P2V5_AUX ; 2 = P3V3_P2V5_P1V8_RVDD
R157  Q_RES  33.2 1% CHIP  pkg 0402LF  page 13 : 1 = UART_BMC_1_TXD_R ; 2 = UART_BMC_1_TXD
R158  Q_RES  33.2 1% CHIP  pkg 0402LF  page 13 : 1 = FM_DBP_CPU_PREQ_GF_R_N ; 2 = FM_DBP_CPU_PREQ_GF_N
R159  Q_RES  33.2 1% CHIP  pkg 0402LF  page 13 : 1 = FM_JTAG_TCK_MUX_BMC_SEL ; 2 = FM_JTAG_TCK_MUX_BMC_SEL_R1
R160  Q_RES  33.2 1% CHIP  pkg 0402LF  page 13 : 1 = RST_RSMRST_N ; 2 = RST_RSMRST_R_N
R161  Q_RES  4.7K 1% CHIP  pkg 0402LF  page 11 : 1 = P3V3_AUX ; 2 = RMII_CSRDV
R162  Q_RES  33.2 1% CHIP  pkg 0402LF  page 12 : 1 = SMB_BMC_MM15_SCL ; 2 = SMB_BMC_MM15_R_SCL
R163  Q_RES  4.7K 1% CHIP  pkg 0402LF  page 11 : 1 = P3V3_AUX ; 2 = FM_CPU_MSMI_CATERR_LVT3_N
R164  Q_RES  100 1% EMPTY  pkg 0402LF  page 27 : 1 = SPI_BMC_BOOT_MISO ; 2 = GND
R165  Q_RES  33.2 1% CHIP  pkg 0402LF  page 12 : 1 = SMB_BMC_MM2_R_SCL ; 2 = SMB_BMC_MM2_SCL
R166  Q_RES  33.2 1% CHIP  pkg 0402LF  page 13 : 1 = IRQ_BMC_CPU_NMI_R ; 2 = IRQ_BMC_CPU_NMI
R167  Q_RES  330 1% CHIP  pkg 0402LF  page 13 : 1 = P3V3_AUX ; 2 = BMC_HEARTBEAT_R_N
R168  Q_RES  33.2 1% CHIP  pkg 0402LF  page 12 : 1 = RST_PLTRST_N ; 2 = RST_PLTRST_R_N
R169  Q_RES  4.7K 1% CHIP  pkg 0402LF  page 11 : 1 = P3V3_AUX ; 2 = RST_PCA9548_SENSOR_N
R170  Q_RES  33.2 1% CHIP  pkg 0402LF  page 13 : 1 = UART_BMC_5_TXD ; 2 = UART_BMC_5_TXD_R
R171  Q_RES  22 1% CHIP  pkg 0402LF  page 13 : 1 = RMII_TXEN_R ; 2 = RMII_TXEN
R172  Q_RES  22 1% CHIP  pkg 0402LF  page 13 : 1 = RMII_TXD0_R ; 2 = RMII_TXD0
